FILE_TYPE = CONNECTIVITY;
{Allegro Design Entry HDL 17.2-2016 S066 (3851973) 4/6/2020}
"PAGE_NUMBER" = 8;
0"NC";
1"SG\g";
2"SG\g";
3"XP3R3V_FPGA\g";
4"XP3R3V\g";
5"XP1R8V_ICP10100\g";
6"SG\g";
7"SG\g";
8"XP1R8V_ICP10100\g";
9"XP1R8V_ICP10100\g";
10"SG\g";
11"XP1R8V_FPGA\g";
12"BF_ICP10100_I2C_SCL";
13"BF_ICP10100_I2C_SDA";
14"ICP10100_I2C_SCL";
15"BF_ICP10100_I2C_SDA";
16"BF_ICP10100_I2C_SCL";
17"UN$8$PCA9508DPTSSOP8$I51$EN";
18"ICP10100_I2C_SDA";
19"UN$8$ICP10100LGA10$I24$RESV4";
20"R_ICP10100_I2C_SDA";
21"UN$8$ICP10100LGA10$I24$RESV5";
22"UN$8$ICP10100LGA10$I24$RESV2";
23"UN$8$ICP10100LGA10$I24$RESV1";
24"UN$8$ICP10100LGA10$I24$RESV3";
25"R_ICP10100_I2C_SCL";
%"VCC"
"1","(-2700,9100)","0","cls","I13";
;
BODY_TYPE"PLUMBING"
CDS_LIB"cls"
CDS_LMAN_SYM_OUTLINE"-250,250,250,-250"
VOLTAGE"1.8V"
HDL_POWER"XP1R8V_FPGA";
"$PIN0"11;
%"CAPACITOR"
"2","(-2950,8500)","2","passive","I16";
;
$LOCATION"C276"
CDS_LOCATION"C276"
$SEC"1"
CDS_SEC"1"
CDS_LMAN_SYM_OUTLINE"-50,0,50,-50"
CDS_LIB"passive"
CLS_PN"G105-0B104-EK"
TOLERANCE"10%"
VALUE"0.1UF"
VOLTAGE"25V"
PACKAGE"0402";
"2"
$PN"2"10;
"1"
$PN"1"11;
%"FERRITEBEAD"
"1","(-3300,8900)","2","passive","I18";
;
$LOCATION"L18"
CDS_LOCATION"L18"
$SEC"1"
CDS_SEC"1"
CDS_LMAN_SYM_OUTLINE"0,0,200,-100"
CDS_LIB"passive"
CLS_PN"G191-10097-01"
TOLERANCE"25%"
DCR"1300MA 0.15OHM"
PACKAGE"0603"
VALUE"600OHM";
"2"
$PN"2"9;
"1"
$PN"1"11;
%"CAPACITOR"
"2","(-3950,8500)","2","passive","I19";
;
$LOCATION"C278"
CDS_LOCATION"C278"
$SEC"1"
CDS_SEC"1"
TOLERANCE"10%"
CDS_LIB"passive"
CDS_LMAN_SYM_OUTLINE"-50,0,50,-50"
CLS_PN"G105-0B104-EK"
PACKAGE"0402"
VOLTAGE"25V"
VALUE"0.1UF";
"2"
$PN"2"10;
"1"
$PN"1"9;
%"GND_SG"
"1","(-4800,7900)","2","cls","I20";
;
BODY_TYPE"PLUMBING"
CDS_LMAN_SYM_OUTLINE"0,0,100,-50"
CDS_LIB"cls"
HDL_POWER"SG";
"SGND"10;
%"CAPACITOR"
"2","(-4350,8500)","2","passive","I21";
;
$LOCATION"C277"
CDS_LOCATION"C277"
$SEC"1"
CDS_SEC"1"
TOLERANCE"20%"
CLS_PN"G105-0C106-BM"
CDS_LMAN_SYM_OUTLINE"-50,0,50,-50"
CDS_LIB"passive"
VOLTAGE"6.3V"
PACKAGE"0402"
VALUE"10UF";
"2"
$PN"2"10;
"1"
$PN"1"9;
%"VCC"
"1","(-4900,9100)","0","cls","I22";
;
BODY_TYPE"PLUMBING"
CDS_LMAN_SYM_OUTLINE"-250,250,250,-250"
CDS_LIB"cls"
HDL_POWER"XP1R8V_ICP10100"
VOLTAGE"1.8V";
"$PIN0"9;
%"VCC"
"1","(-9600,9800)","0","cls","I23";
;
BODY_TYPE"PLUMBING"
CDS_LIB"cls"
CDS_LMAN_SYM_OUTLINE"-250,250,250,-250"
HDL_POWER"XP1R8V_ICP10100"
VOLTAGE"1.8V";
"$PIN0"8;
%"ICP_10100_LGA10"
"1","(-5900,8950)","2","analog","I24";
;
$LOCATION"U28"
CDS_LOCATION"U28"
$SEC"1"
CDS_SEC"1"
CDS_LIB"analog"
CDS_LMAN_SYM_OUTLINE"0,0,750,-800"
VALUE"ICP-10100"
CLS_PN"A222-00002-FB";
"VDD"
$PN"10"9;
"GND_2"
$PN"9"7;
"GND_1"
$PN"8"7;
"RESV_5"
$PN"7"21;
"RESV_4"
$PN"6"19;
"RESV_3"
$PN"5"24;
"SDA"
$PN"4"20;
"RESV_2"
$PN"3"22;
"SCL"
$PN"2"25;
"RESV_1"
$PN"1"23;
%"GND_SG"
"1","(-6850,8000)","2","cls","I25";
;
BODY_TYPE"PLUMBING"
CDS_LMAN_SYM_OUTLINE"0,0,100,-50"
CDS_LIB"cls"
HDL_POWER"SG";
"SGND"7;
%"RESISTOR"
"2","(-9550,9400)","0","passive","I3";
;
$LOCATION"R70"
CDS_LOCATION"R70"
$SEC"1"
CDS_SEC"1"
TOLERANCE"1%"
CDS_LIB"passive"
CDS_LMAN_SYM_OUTLINE"-50,50,50,-100"
CLS_PN"G155-14701-01"
PACKAGE"0402"
VALUE"4.7KOHM";
"1"
$PN"1"8;
"2"
$PN"2"13;
%"RESISTOR"
"1","(-5350,8250)","0","passive","I30";
;
$LOCATION"R351"
CDS_LOCATION"R351"
$SEC"1"
CDS_SEC"1"
TOLERANCE"-"
CDS_LIB"passive"
CDS_LMAN_SYM_OUTLINE"-50,50,100,-50"
CLS_PN"G155-100R0-J0"
VALUE"0OHM"
PACKAGE"0402";
"1"
$PN"1"21;
"2"
$PN"2"10;
%"RESISTOR"
"1","(-5350,8350)","0","passive","I31";
;
LOCATION"R350"
$SEC"1"
CDS_SEC"1"
TOLERANCE"-"
CDS_LMAN_SYM_OUTLINE"-50,50,100,-50"
CDS_LIB"passive"
CLS_PN"G155-100R0-J0"
VALUE"0OHM"
PACKAGE"0402";
"1"
$PN"1"19;
"2"
$PN"2"9;
%"RESISTOR"
"1","(-5350,8450)","0","passive","I32";
;
LOCATION"R347"
$SEC"1"
CDS_SEC"1"
TOLERANCE"-"
CDS_LMAN_SYM_OUTLINE"-50,50,100,-50"
CDS_LIB"passive"
CLS_PN"G155-100R0-J0"
VALUE"0OHM"
PACKAGE"0402";
"1"
$PN"1"24;
"2"
$PN"2"9;
%"RESISTOR"
"1","(-5350,8550)","0","passive","I33";
;
LOCATION"R346"
$SEC"1"
CDS_SEC"1"
TOLERANCE"-"
CDS_LMAN_SYM_OUTLINE"-50,50,100,-50"
CDS_LIB"passive"
CLS_PN"G155-100R0-J0"
VALUE"0OHM"
PACKAGE"0402";
"1"
$PN"1"22;
"2"
$PN"2"10;
%"RESISTOR"
"1","(-5350,8650)","0","passive","I34";
;
LOCATION"R343"
$SEC"1"
CDS_SEC"1"
TOLERANCE"-"
CDS_LMAN_SYM_OUTLINE"-50,50,100,-50"
CDS_LIB"passive"
CLS_PN"G155-100R0-J0"
VALUE"0OHM"
PACKAGE"0402";
"1"
$PN"1"23;
"2"
$PN"2"10;
%"GND_SG"
"1","(-4600,5400)","0","cls","I35";
;
BODY_TYPE"PLUMBING"
CDS_LMAN_SYM_OUTLINE"0,0,100,-50"
CDS_LIB"cls"
HDL_POWER"SG";
"SGND"2;
%"GND_SG"
"1","(-3850,5400)","0","cls","I38";
;
BODY_TYPE"PLUMBING"
CDS_LIB"cls"
CDS_LMAN_SYM_OUTLINE"0,0,100,-50"
HDL_POWER"SG";
"SGND"1;
%"CAPACITOR"
"2","(-4550,5700)","0","passive","I39";
;
$LOCATION"C312"
CDS_LOCATION"C312"
$SEC"1"
CDS_SEC"1"
CDS_LIB"passive"
CDS_LMAN_SYM_OUTLINE"-50,0,50,-50"
CLS_PN"G105-0B104-CK"
TOLERANCE"10%"
PACKAGE"0402"
VALUE"0.1UF"
VOLTAGE"10V";
"2"
$PN"2"2;
"1"
$PN"1"4;
%"CAPACITOR"
"2","(-3800,5700)","0","passive","I41";
;
$LOCATION"C313"
CDS_LOCATION"C313"
$SEC"1"
CDS_SEC"1"
CDS_LIB"passive"
CDS_LMAN_SYM_OUTLINE"-50,0,50,-50"
TOLERANCE"10%"
CLS_PN"G105-0B104-CK"
PACKAGE"0402"
VALUE"0.1UF"
VOLTAGE"10V";
"2"
$PN"2"1;
"1"
$PN"1"5;
%"RESISTOR"
"2","(-9100,9400)","0","passive","I5";
;
$LOCATION"R71"
CDS_LOCATION"R71"
$SEC"1"
CDS_SEC"1"
TOLERANCE"1%"
CDS_LIB"passive"
CDS_LMAN_SYM_OUTLINE"-50,50,50,-100"
CLS_PN"G155-14701-01"
VALUE"4.7KOHM"
PACKAGE"0402";
"1"
$PN"1"8;
"2"
$PN"2"12;
%"PCA9508DP_TSSOP8"
"1","(-8600,6250)","0","stdlogic","I51";
;
$LOCATION"U32"
CDS_LOCATION"U32"
$SEC"1"
CDS_SEC"1"
CDS_LIB"stdlogic"
CDS_LMAN_SYM_OUTLINE"0,0,600,-450"
CLS_PN"G223-10278-01";
"SCLB"
$PN"7"14;
"SDAB"
$PN"6"18;
"EN"
$PN"5"17;
"SDAA"
$PN"3"15;
"SCLA"
$PN"2"16;
%"PCA9508DP_TSSOP8"
"2","(-3400,5850)","1","stdlogic","I52";
;
$LOCATION"U32"
CDS_LOCATION"U32"
$SEC"2"
CDS_SEC"2"
CDS_LMAN_SYM_OUTLINE"0,0,400,-650"
CDS_LIB"stdlogic"
CLS_PN"G223-10278-01";
"VCC_B"
$PN"8"4;
"GND"
$PN"4"6;
"VCC_A"
$PN"1"5;
%"GND_SG"
"1","(-2500,5550)","0","cls","I53";
;
BODY_TYPE"PLUMBING"
CDS_LMAN_SYM_OUTLINE"0,0,100,-50"
CDS_LIB"cls"
HDL_POWER"SG";
"SGND"6;
%"VCC"
"1","(-3850,6400)","0","cls","I54";
;
BODY_TYPE"PLUMBING"
CDS_LIB"cls"
CDS_LMAN_SYM_OUTLINE"-250,250,250,-250"
HDL_POWER"XP1R8V_ICP10100"
VOLTAGE"1.8V";
"$PIN0"5;
%"RESISTOR"
"1","(-8600,8750)","0","passive","I6";
;
$LOCATION"R73"
CDS_LOCATION"R73"
$SEC"1"
CDS_SEC"1"
TOLERANCE"1%"
CLS_PN"G155-133R0-01"
SIGNAL_MODEL"DEFAULT_RESISTOR_33OHM_2_1"
CDS_LMAN_SYM_OUTLINE"-50,50,100,-50"
CDS_LIB"passive"
VALUE"33OHM"
PACKAGE"0402";
"1"
$PN"1"12;
"2"
$PN"2"25;
%"RESISTOR"
"1","(-8350,5550)","0","passive","I63";
;
$LOCATION"R315"
CDS_LOCATION"R315"
$SEC"1"
CDS_SEC"1"
TOLERANCE"-"
CDS_LIB"passive"
CDS_LMAN_SYM_OUTLINE"-50,50,100,-50"
CLS_PN"G155-100R0-J0"
NO_ASSY"TRUE"
VALUE"0OHM"
PACKAGE"0402";
"1"
$PN"1"14;
"2"
$PN"2"16;
%"RESISTOR"
"1","(-8350,5450)","0","passive","I64";
;
$LOCATION"R316"
CDS_LOCATION"R316"
$SEC"1"
CDS_SEC"1"
TOLERANCE"-"
CLS_PN"G155-100R0-J0"
CDS_LMAN_SYM_OUTLINE"-50,50,100,-50"
CDS_LIB"passive"
NO_ASSY"TRUE"
VALUE"0OHM"
PACKAGE"0402";
"1"
$PN"1"18;
"2"
$PN"2"15;
%"RESISTOR"
"2","(-9550,6600)","0","passive","I69";
;
$LOCATION"R282"
CDS_LOCATION"R282"
$SEC"1"
CDS_SEC"1"
TOLERANCE"1%"
CLS_PN"G155-14701-01"
CDS_LMAN_SYM_OUTLINE"-50,50,50,-100"
CDS_LIB"passive"
PACKAGE"0402"
VALUE"4.7KOHM";
"1"
$PN"1"3;
"2"
$PN"2"14;
%"RESISTOR"
"1","(-8600,8850)","0","passive","I7";
;
$LOCATION"R72"
CDS_LOCATION"R72"
$SEC"1"
CDS_SEC"1"
TOLERANCE"1%"
CLS_PN"G155-133R0-01"
CDS_LIB"passive"
CDS_LMAN_SYM_OUTLINE"-50,50,100,-50"
SIGNAL_MODEL"DEFAULT_RESISTOR_33OHM_2_1"
VALUE"33OHM"
PACKAGE"0402";
"1"
$PN"1"13;
"2"
$PN"2"20;
%"RESISTOR"
"2","(-10000,6600)","0","passive","I70";
;
$LOCATION"R281"
CDS_LOCATION"R281"
$SEC"1"
CDS_SEC"1"
TOLERANCE"1%"
CLS_PN"G155-14701-01"
CDS_LMAN_SYM_OUTLINE"-50,50,50,-100"
CDS_LIB"passive"
VALUE"4.7KOHM"
PACKAGE"0402";
"1"
$PN"1"3;
"2"
$PN"2"18;
%"RESISTOR"
"1","(-9100,6650)","3","passive","I71";
;
$LOCATION"R314"
CDS_LOCATION"R314"
$SEC"1"
CDS_SEC"1"
TOLERANCE"1%"
CDS_LIB"passive"
CDS_LMAN_SYM_OUTLINE"-50,50,100,-50"
CLS_PN"G155-14701-01"
VALUE"4.7KOHM"
PACKAGE"0402";
"1"
$PN"1"3;
"2"
$PN"2"17;
%"VCC"
"1","(-4600,6400)","0","cls","I72";
;
BODY_TYPE"PLUMBING"
CDS_LMAN_SYM_OUTLINE"-250,250,250,-250"
CDS_LIB"cls"
HDL_POWER"XP3R3V"
VOLTAGE"3.3";
"$PIN0"4;
%"VCC"
"1","(-9150,7100)","0","cls","I73";
;
CDS_LIB"cls"
CDS_LMAN_SYM_OUTLINE"-250,250,250,-250"
BODY_TYPE"PLUMBING"
HDL_POWER"XP3R3V_FPGA"
VOLTAGE"3.3V";
"$PIN0"3;
END.
